# BASEBOARD_FAB2 (Tioga Pass) — schematic netlist excerpt (pin names and nets, part order shuffled) for the footprints in the layout excerpt that follows; sources: Cadence DE-HDL packaged netlist, KiCad conversion of Wiwynn_Tioga_Pass_MB.brd

J9L1  SCONN288_H44441003  SCONN  pkg PIP  page 88
  \12v\(1)  = P12V_NVDIMM_KLM
  VSS(93)  = GND
  DQ(4)  = M_M_DQ<4>
  VSS(92)  = GND
  DQ(0)  = M_M_DQ<0>
  VSS(91)  = GND
  DQS9P  = M_M_DQS_DP<9>
  DQS9N  = M_M_DQS_DN<9>
  VSS(90)  = GND
  DQ(6)  = M_M_DQ<6>
  VSS(89)  = GND
  DQ(2)  = M_M_DQ<2>
  VSS(88)  = GND
  DQ(12)  = M_M_DQ<12>
  VSS(87)  = GND
  DQ(8)  = M_M_DQ<8>
  VSS(86)  = GND
  DQS10P  = M_M_DQS_DP<10>
  DQS10N  = M_M_DQS_DN<10>
  VSS(85)  = GND
  DQ(14)  = M_M_DQ<14>
  VSS(84)  = GND
  DQ(10)  = M_M_DQ<10>
  VSS(83)  = GND
  DQ(20)  = M_M_DQ<20>
  VSS(82)  = GND
  DQ(16)  = M_M_DQ<16>
  VSS(81)  = GND
  DQS11P  = M_M_DQS_DP<11>
  DQS11N  = M_M_DQS_DN<11>
  VSS(80)  = GND
  DQ(22)  = M_M_DQ<22>
  VSS(79)  = GND
  DQ(18)  = M_M_DQ<18>
  VSS(78)  = GND
  DQ(28)  = M_M_DQ<28>
  VSS(77)  = GND
  DQ(24)  = M_M_DQ<24>
  VSS(76)  = GND
  DQS12P  = M_M_DQS_DP<12>
  DQS12N  = M_M_DQS_DN<12>
  VSS(75)  = GND
  DQ(30)  = M_M_DQ<30>
  VSS(74)  = GND
  DQ(26)  = M_M_DQ<26>
  VSS(73)  = GND
  CB(4)  = M_M_ECC<4>
  VSS(72)  = GND
  CB(0)  = M_M_ECC<0>
  VSS(71)  = GND
  DQS17P  = M_M_DQS_DP<17>
  DQS17N  = M_M_DQS_DN<17>
  VSS(70)  = GND
  CB(6)  = M_M_ECC<6>
  VSS(69)  = GND
  CB(2)  = M_M_ECC<2>
  VSS(68)  = GND
  RESET_N  = M_KLM_RST_N
  VDD(25)  = PVDDQ_KLM
  CKE(0)  = M_M_CKE<2>
  VDD(24)  = PVDDQ_KLM
  ACT_N  = M_M_ACT_N
  BG(0)  = M_M_BG<0>
  VDD(23)  = PVDDQ_KLM
  A12  = M_M_MA<12>
  A9  = M_M_MA<9>
  VDD(22)  = PVDDQ_KLM
  A8  = M_M_MA<8>
  A6  = M_M_MA<6>
  VDD(21)  = PVDDQ_KLM
  A3  = M_M_MA<3>
  A1  = M_M_MA<1>
  VDD(20)  = PVDDQ_KLM
  CK0P  = M_M_CLK_DP<2>
  CK0N  = M_M_CLK_DN<2>
  VDD(19)  = PVDDQ_KLM
  VTT(1)  = PVTT_KLM
  EVENT_N  = FM_DIMM_EVENT_COD_N
  A0  = M_M_MA<0>
  VDD(18)  = PVDDQ_KLM
  BA(0)  = M_M_BA<0>
  A16_RAS_N  = M_M_MA<16>
  VDD(17)  = PVDDQ_KLM
  S0_N  = M_M_CS_N<4>
  VDD(16)  = PVDDQ_KLM
  A15_CAS_N  = M_M_MA<15>
  ODT(0)  = M_M_ODT<2>
  VDD(15)  = PVDDQ_KLM
  S1_N  = M_M_CS_N<5>
  VDD(14)  = PVDDQ_KLM
  ODT(1)  = M_M_ODT<3>
  VDD(13)  = PVDDQ_KLM
  S2_N_C(0)  = M_M_CS_N<6>
  VSS(67)  = GND
  DQ(36)  = M_M_DQ<36>
  VSS(66)  = GND
  DQ(32)  = M_M_DQ<32>
  VSS(65)  = GND
  DQS13P  = M_M_DQS_DP<13>
  DQS13N  = M_M_DQS_DN<13>
  VSS(64)  = GND
  DQ(38)  = M_M_DQ<38>
  VSS(63)  = GND
  DQ(34)  = M_M_DQ<34>
  VSS(62)  = GND
  DQ(44)  = M_M_DQ<44>
  VSS(61)  = GND
  DQ(40)  = M_M_DQ<40>
  VSS(60)  = GND
  DQS14P  = M_M_DQS_DP<14>
  DQS14N  = M_M_DQS_DN<14>
  VSS(59)  = GND
  DQ(46)  = M_M_DQ<46>
  VSS(58)  = GND
  DQ(42)  = M_M_DQ<42>
  VSS(57)  = GND
  DQ(52)  = M_M_DQ<52>
  VSS(56)  = GND
  DQ(48)  = M_M_DQ<48>
  VSS(55)  = GND
  DQS15P  = M_M_DQS_DP<15>
  DQS15N  = M_M_DQS_DN<15>
  VSS(54)  = GND
  DQ(54)  = M_M_DQ<54>
  VSS(53)  = GND
  DQ(50)  = M_M_DQ<50>
  VSS(52)  = GND
  DQ(60)  = M_M_DQ<60>
  VSS(51)  = GND
  DQ(56)  = M_M_DQ<56>
  VSS(50)  = GND
  DQS16P  = M_M_DQS_DP<16>
  DQS16N  = M_M_DQS_DN<16>
  VSS(49)  = GND
  DQ(62)  = M_M_DQ<62>
  VSS(48)  = GND
  DQ(58)  = M_M_DQ<58>
  VSS(47)  = GND
  SA(0)  = PVPP_KLM
  SA(1)  = GND
  SCL  = SMB_DDR_KLM_VPP_SCL
  VPP(4)  = PVPP_KLM
  VPP(3)  = PVPP_KLM
  RFU(2)  = TP_CH_M_DIMM_M1_RFU_2
  \12v\(0)  = P12V_NVDIMM_KLM
  VREFCA  = M_M_VREF
  VSS(46)  = GND
  DQ(5)  = M_M_DQ<5>
  VSS(45)  = GND
  DQ(1)  = M_M_DQ<1>
  VSS(44)  = GND
  DQS0N  = M_M_DQS_DN<0>
  DQS0P  = M_M_DQS_DP<0>
  VSS(43)  = GND
  DQ(7)  = M_M_DQ<7>
  VSS(42)  = GND
  DQ(3)  = M_M_DQ<3>
  VSS(41)  = GND
  DQ(13)  = M_M_DQ<13>
  VSS(40)  = GND
  DQ(9)  = M_M_DQ<9>
  VSS(39)  = GND
  DQS1N  = M_M_DQS_DN<1>
  DQS1P  = M_M_DQS_DP<1>
  VSS(38)  = GND
  DQ(15)  = M_M_DQ<15>
  VSS(37)  = GND
  DQ(11)  = M_M_DQ<11>
  VSS(36)  = GND
  DQ(21)  = M_M_DQ<21>
  VSS(35)  = GND
  DQ(17)  = M_M_DQ<17>
  VSS(34)  = GND
  DQS2N  = M_M_DQS_DN<2>
  DQS2P  = M_M_DQS_DP<2>
  VSS(33)  = GND
  DQ(23)  = M_M_DQ<23>
  VSS(32)  = GND
  DQ(19)  = M_M_DQ<19>
  VSS(31)  = GND
  DQ(29)  = M_M_DQ<29>
  VSS(30)  = GND
  DQ(25)  = M_M_DQ<25>
  VSS(29)  = GND
  DQS3N  = M_M_DQS_DN<3>
  DQS3P  = M_M_DQS_DP<3>
  VSS(28)  = GND
  DQ(31)  = M_M_DQ<31>
  VSS(27)  = GND
  DQ(27)  = M_M_DQ<27>
  VSS(26)  = GND
  CB(5)  = M_M_ECC<5>
  VSS(25)  = GND
  CB(1)  = M_M_ECC<1>
  VSS(24)  = GND
  DQS8N  = M_M_DQS_DN<8>
  DQS8P  = M_M_DQS_DP<8>
  VSS(23)  = GND
  CB(7)  = M_M_ECC<7>
  VSS(22)  = GND
  CB(3)  = M_M_ECC<3>
  VSS(21)  = GND
  CKE(1)  = M_M_CKE<3>
  VDD(12)  = PVDDQ_KLM
  RFU(0)  = TP_CH_M_DIMM_M1_RFU_0
  VDD(11)  = PVDDQ_KLM
  BG(1)  = M_M_BG<1>
  ALERT_N  = M_M_ALERT_N
  VDD(10)  = PVDDQ_KLM
  A11  = M_M_MA<11>
  A7  = M_M_MA<7>
  VDD(9)  = PVDDQ_KLM
  A5  = M_M_MA<5>
  A4  = M_M_MA<4>
  VDD(8)  = PVDDQ_KLM
  A2  = M_M_MA<2>
  VDD(7)  = PVDDQ_KLM
  CK1P  = M_M_CLK_DP<3>
  CK1N  = M_M_CLK_DN<3>
  VDD(6)  = PVDDQ_KLM
  VTT(0)  = PVTT_KLM
  PAR  = M_M_PAR
  VDD(5)  = PVDDQ_KLM
  BA(1)  = M_M_BA<1>
  A10  = M_M_MA<10>
  VDD(4)  = PVDDQ_KLM
  RFU(1)  = TP_CH_M_DIMM_M1_RFU_1
  A14_WE_N  = M_M_MA<14>
  VDD(3)  = PVDDQ_KLM
  SAVE_N_NC  = FM_ADR_COMPLETE_KLM_N
  VDD(2)  = PVDDQ_KLM
  A13  = M_M_MA<13>
  VDD(1)  = PVDDQ_KLM
  A17  = M_M_MA<17>
  C(2)  = M_M_C<2>
  VDD(0)  = PVDDQ_KLM
  S3_N_C(1)  = M_M_CS_N<7>
  SA(2)  = PVPP_KLM
  VSS(20)  = GND
  DQ(37)  = M_M_DQ<37>
  VSS(19)  = GND
  DQ(33)  = M_M_DQ<33>
  VSS(18)  = GND
  DQS4N  = M_M_DQS_DN<4>
  DQS4P  = M_M_DQS_DP<4>
  VSS(17)  = GND
  DQ(39)  = M_M_DQ<39>
  VSS(16)  = GND
  DQ(35)  = M_M_DQ<35>
  VSS(15)  = GND
  DQ(45)  = M_M_DQ<45>
  VSS(14)  = GND
  DQ(41)  = M_M_DQ<41>
  VSS(13)  = GND
  DQS5N  = M_M_DQS_DN<5>
  DQS5P  = M_M_DQS_DP<5>
  VSS(12)  = GND
  DQ(47)  = M_M_DQ<47>
  VSS(11)  = GND
  DQ(43)  = M_M_DQ<43>
  VSS(10)  = GND
  DQ(53)  = M_M_DQ<53>
  VSS(9)  = GND
  DQ(49)  = M_M_DQ<49>
  VSS(8)  = GND
  DQS6N  = M_M_DQS_DN<6>
  DQS6P  = M_M_DQS_DP<6>
  VSS(7)  = GND
  DQ(55)  = M_M_DQ<55>
  VSS(6)  = GND
  DQ(51)  = M_M_DQ<51>
  VSS(5)  = GND
  DQ(61)  = M_M_DQ<61>
  VSS(4)  = GND
  DQ(57)  = M_M_DQ<57>
  VSS(3)  = GND
  DQS7N  = M_M_DQS_DN<7>
  DQS7P  = M_M_DQS_DP<7>
  VSS(2)  = GND
  DQ(63)  = M_M_DQ<63>
  VSS(1)  = GND
  DQ(59)  = M_M_DQ<59>
  VSS(0)  = GND
  VDDSPD  = PVPP_KLM
  SDA  = SMB_DDR_KLM_VPP_SDA
  VPP(1)  = PVPP_KLM
  VPP(0)  = PVPP_KLM
  VPP(2)  = PVPP_KLM

(kicad_pcb
	(version 20260206)
	(generator "pcbnew")
	(generator_version "10.0")
	(general
		(thickness 1.6)
		(legacy_teardrops no)
	)
	(paper "A4")
	(title_block
		(title "Wiwynn_Tioga_Pass_MB.brd")
		(comment 1 "Tioga Pass / footprint 2717 of 4770 (J9L1), pads 1-50 of 291")
	)
	(layers
		(0 "F.Cu" signal "TOP")
		(4 "In1.Cu" signal "L2GND")
		(6 "In2.Cu" signal "L3")
		(8 "In3.Cu" signal "L4GND")
		(10 "In4.Cu" signal "L5")
		(12 "In5.Cu" signal "L6GND")
		(14 "In6.Cu" signal "L7VCC")
		(16 "In7.Cu" signal "L8VCC")
		(18 "In8.Cu" signal "L9GND")
		(20 "In9.Cu" signal "L10")
		(22 "In10.Cu" signal "L11GND")
		(24 "In11.Cu" signal "L12")
		(26 "In12.Cu" signal "L13GND")
		(2 "B.Cu" signal "BOTTOM")
		(9 "F.Adhes" user "F.Adhesive")
		(11 "B.Adhes" user "B.Adhesive")
		(13 "F.Paste" user "Package Geometry/Pastemask Top")
		(15 "B.Paste" user "Package Geometry/Pastemask Bottom")
		(5 "F.SilkS" user "Ref Des/Silkscreen Top")
		(7 "B.SilkS" user "Ref Des/Silkscreen Bottom")
		(1 "F.Mask" user "Board Geometry/Soldermask Top")
		(3 "B.Mask" user "Board Geometry/Soldermask Bottom")
		(17 "Dwgs.User" user "User.Drawings")
		(19 "Cmts.User" user "User.Comments")
		(21 "Eco1.User" user "User.Eco1")
		(23 "Eco2.User" user "User.Eco2")
		(25 "Edge.Cuts" user "Board Geometry/Outline")
		(27 "Margin" user)
		(31 "F.CrtYd" user "Package Geometry/Place Bound Top")
		(29 "B.CrtYd" user "Package Geometry/Place Bound Bottom")
		(35 "F.Fab" user "Ref Des/Assembly Top")
		(33 "B.Fab" user "Ref Des/Assembly Bottom")
	)
	(footprint ""
		(layer "B.Cu")
		(at 29.699458 -152.078436 90)
		(property "Reference" "J9L1"
			(at 2.200148 37.737542 0)
			(unlocked yes)
			(layer "B.SilkS")
			(effects
				(font
					(size 0.7874 0.5842)
					(thickness 0.1524)
				)
				(justify left mirror)
			)
		)
		(property "Value" ""
			(at 0 0 90)
			(layer "B.Fab")
			(effects
				(font
					(size 1.27 1.27)
				)
				(justify mirror)
			)
		)
		(duplicate_pad_numbers_are_jumpers no)
		(pad "" thru_hole circle
			(at -2.29997 -5.649976 270)
			(size 2.8194 2.8194)
			(drill 2.4384)
			(layers "*.Cu" "*.Mask")
			(remove_unused_layers no)
			(clearance 0.127)
			(thermal_gap 0.127)
		)
		(pad "" thru_hole oval
			(at -2.29997 68.90004 270)
			(size 2.8194 1.5748)
			(drill oval 2.4384 1.1938)
			(layers "*.Cu" "*.Mask")
			(remove_unused_layers no)
			(clearance 0.127)
			(thermal_gap 0.127)
		)
		(pad "" thru_hole circle
			(at -2.29997 132.299964 270)
			(size 2.8194 2.8194)
			(drill 2.4384)
			(layers "*.Cu" "*.Mask")
			(remove_unused_layers no)
			(clearance 0.127)
			(thermal_gap 0.127)
		)
		(pad "1" smd rect
			(at 0 0 270)
			(size 1.8034 0.508)
			(layers "B.Cu" "B.Mask" "B.Paste")
			(net "P12V_NVDIMM_KLM")
		)
		(pad "2" smd rect
			(at 0 0.849884 270)
			(size 1.8034 0.508)
			(layers "B.Cu" "B.Mask" "B.Paste")
			(net "GND")
		)
		(pad "3" smd rect
			(at 0 1.700022 270)
			(size 1.8034 0.508)
			(layers "B.Cu" "B.Mask" "B.Paste")
			(net "M_M_DQ<4>")
		)
		(pad "4" smd rect
			(at 0 2.549906 270)
			(size 1.8034 0.508)
			(layers "B.Cu" "B.Mask" "B.Paste")
			(net "GND")
		)
		(pad "5" smd rect
			(at 0 3.400044 270)
			(size 1.8034 0.508)
			(layers "B.Cu" "B.Mask" "B.Paste")
			(net "M_M_DQ<0>")
		)
		(pad "6" smd rect
			(at 0 4.249928 270)
			(size 1.8034 0.508)
			(layers "B.Cu" "B.Mask" "B.Paste")
			(net "GND")
		)
		(pad "7" smd rect
			(at 0 5.100066 270)
			(size 1.8034 0.508)
			(layers "B.Cu" "B.Mask" "B.Paste")
			(net "M_M_DQS_DP<9>")
		)
		(pad "8" smd rect
			(at 0 5.94995 270)
			(size 1.8034 0.508)
			(layers "B.Cu" "B.Mask" "B.Paste")
			(net "M_M_DQS_DN<9>")
		)
		(pad "9" smd rect
			(at 0 6.800088 270)
			(size 1.8034 0.508)
			(layers "B.Cu" "B.Mask" "B.Paste")
			(net "GND")
		)
		(pad "10" smd rect
			(at 0 7.649972 270)
			(size 1.8034 0.508)
			(layers "B.Cu" "B.Mask" "B.Paste")
			(net "M_M_DQ<6>")
		)
		(pad "11" smd rect
			(at 0 8.50011 270)
			(size 1.8034 0.508)
			(layers "B.Cu" "B.Mask" "B.Paste")
			(net "GND")
		)
		(pad "12" smd rect
			(at 0 9.349994 270)
			(size 1.8034 0.508)
			(layers "B.Cu" "B.Mask" "B.Paste")
			(net "M_M_DQ<2>")
		)
		(pad "13" smd rect
			(at 0 10.199878 270)
			(size 1.8034 0.508)
			(layers "B.Cu" "B.Mask" "B.Paste")
			(net "GND")
		)
		(pad "14" smd rect
			(at 0 11.050016 270)
			(size 1.8034 0.508)
			(layers "B.Cu" "B.Mask" "B.Paste")
			(net "M_M_DQ<12>")
		)
		(pad "15" smd rect
			(at 0 11.8999 270)
			(size 1.8034 0.508)
			(layers "B.Cu" "B.Mask" "B.Paste")
			(net "GND")
		)
		(pad "16" smd rect
			(at 0 12.750038 270)
			(size 1.8034 0.508)
			(layers "B.Cu" "B.Mask" "B.Paste")
			(net "M_M_DQ<8>")
		)
		(pad "17" smd rect
			(at 0 13.599922 270)
			(size 1.8034 0.508)
			(layers "B.Cu" "B.Mask" "B.Paste")
			(net "GND")
		)
		(pad "18" smd rect
			(at 0 14.45006 270)
			(size 1.8034 0.508)
			(layers "B.Cu" "B.Mask" "B.Paste")
			(net "M_M_DQS_DP<10>")
		)
		(pad "19" smd rect
			(at 0 15.299944 270)
			(size 1.8034 0.508)
			(layers "B.Cu" "B.Mask" "B.Paste")
			(net "M_M_DQS_DN<10>")
		)
		(pad "20" smd rect
			(at 0 16.150082 270)
			(size 1.8034 0.508)
			(layers "B.Cu" "B.Mask" "B.Paste")
			(net "GND")
		)
		(pad "21" smd rect
			(at 0 16.999966 270)
			(size 1.8034 0.508)
			(layers "B.Cu" "B.Mask" "B.Paste")
			(net "M_M_DQ<14>")
		)
		(pad "22" smd rect
			(at 0 17.850104 270)
			(size 1.8034 0.508)
			(layers "B.Cu" "B.Mask" "B.Paste")
			(net "GND")
		)
		(pad "23" smd rect
			(at 0 18.699988 270)
			(size 1.8034 0.508)
			(layers "B.Cu" "B.Mask" "B.Paste")
			(net "M_M_DQ<10>")
		)
		(pad "24" smd rect
			(at 0 19.550126 270)
			(size 1.8034 0.508)
			(layers "B.Cu" "B.Mask" "B.Paste")
			(net "GND")
		)
		(pad "25" smd rect
			(at 0 20.40001 270)
			(size 1.8034 0.508)
			(layers "B.Cu" "B.Mask" "B.Paste")
			(net "M_M_DQ<20>")
		)
		(pad "26" smd rect
			(at 0 21.249894 270)
			(size 1.8034 0.508)
			(layers "B.Cu" "B.Mask" "B.Paste")
			(net "GND")
		)
		(pad "27" smd rect
			(at 0 22.100032 270)
			(size 1.8034 0.508)
			(layers "B.Cu" "B.Mask" "B.Paste")
			(net "M_M_DQ<16>")
		)
		(pad "28" smd rect
			(at 0 22.949916 270)
			(size 1.8034 0.508)
			(layers "B.Cu" "B.Mask" "B.Paste")
			(net "GND")
		)
		(pad "29" smd rect
			(at 0 23.800054 270)
			(size 1.8034 0.508)
			(layers "B.Cu" "B.Mask" "B.Paste")
			(net "M_M_DQS_DP<11>")
		)
		(pad "30" smd rect
			(at 0 24.649938 270)
			(size 1.8034 0.508)
			(layers "B.Cu" "B.Mask" "B.Paste")
			(net "M_M_DQS_DN<11>")
		)
		(pad "31" smd rect
			(at 0 25.500076 270)
			(size 1.8034 0.508)
			(layers "B.Cu" "B.Mask" "B.Paste")
			(net "GND")
		)
		(pad "32" smd rect
			(at 0 26.34996 270)
			(size 1.8034 0.508)
			(layers "B.Cu" "B.Mask" "B.Paste")
			(net "M_M_DQ<22>")
		)
		(pad "33" smd rect
			(at 0 27.200098 270)
			(size 1.8034 0.508)
			(layers "B.Cu" "B.Mask" "B.Paste")
			(net "GND")
		)
		(pad "34" smd rect
			(at 0 28.049982 270)
			(size 1.8034 0.508)
			(layers "B.Cu" "B.Mask" "B.Paste")
			(net "M_M_DQ<18>")
		)
		(pad "35" smd rect
			(at 0 28.90012 270)
			(size 1.8034 0.508)
			(layers "B.Cu" "B.Mask" "B.Paste")
			(net "GND")
		)
		(pad "36" smd rect
			(at 0 29.750004 270)
			(size 1.8034 0.508)
			(layers "B.Cu" "B.Mask" "B.Paste")
			(net "M_M_DQ<28>")
		)
		(pad "37" smd rect
			(at 0 30.599888 270)
			(size 1.8034 0.508)
			(layers "B.Cu" "B.Mask" "B.Paste")
			(net "GND")
		)
		(pad "38" smd rect
			(at 0 31.450026 270)
			(size 1.8034 0.508)
			(layers "B.Cu" "B.Mask" "B.Paste")
			(net "M_M_DQ<24>")
		)
		(pad "39" smd rect
			(at 0 32.29991 270)
			(size 1.8034 0.508)
			(layers "B.Cu" "B.Mask" "B.Paste")
			(net "GND")
		)
		(pad "40" smd rect
			(at 0 33.150048 270)
			(size 1.8034 0.508)
			(layers "B.Cu" "B.Mask" "B.Paste")
			(net "M_M_DQS_DP<12>")
		)
		(pad "41" smd rect
			(at 0 33.999932 270)
			(size 1.8034 0.508)
			(layers "B.Cu" "B.Mask" "B.Paste")
			(net "M_M_DQS_DN<12>")
		)
		(pad "42" smd rect
			(at 0 34.85007 270)
			(size 1.8034 0.508)
			(layers "B.Cu" "B.Mask" "B.Paste")
			(net "GND")
		)
		(pad "43" smd rect
			(at 0 35.699954 270)
			(size 1.8034 0.508)
			(layers "B.Cu" "B.Mask" "B.Paste")
			(net "M_M_DQ<30>")
		)
		(pad "44" smd rect
			(at 0 36.550092 270)
			(size 1.8034 0.508)
			(layers "B.Cu" "B.Mask" "B.Paste")
			(net "GND")
		)
		(pad "45" smd rect
			(at 0 37.399976 270)
			(size 1.8034 0.508)
			(layers "B.Cu" "B.Mask" "B.Paste")
			(net "M_M_DQ<26>")
		)
		(pad "46" smd rect
			(at 0 38.250114 270)
			(size 1.8034 0.508)
			(layers "B.Cu" "B.Mask" "B.Paste")
			(net "GND")
		)
		(pad "47" smd rect
			(at 0 39.099998 270)
			(size 1.8034 0.508)
			(layers "B.Cu" "B.Mask" "B.Paste")
			(net "M_M_ECC<4>")
		)
	)
)
